(kicad_pcb
	(version 20260206)
	(generator "pcbnew")
	(generator_version "10.0")
	(general
		(thickness 1.6)
		(legacy_teardrops no)
	)
	(paper "A4")
	(title_block
		(title "04192023_DAF0TMB3IC0_F0TG_MB_C_brd_V02_OCP.brd")
		(comment 1 "Grand Teton / footprints 2804-2809 of 8354")
	)
	(layers
		(0 "F.Cu" signal "TOP")
		(4 "In1.Cu" signal "GND")
		(6 "In2.Cu" signal "IN1")
		(8 "In3.Cu" signal "GND1")
		(10 "In4.Cu" signal "IN2")
		(12 "In5.Cu" signal "GND2")
		(14 "In6.Cu" signal "IN3")
		(16 "In7.Cu" signal "GND3")
		(18 "In8.Cu" signal "VCC")
		(20 "In9.Cu" signal "VCC1")
		(22 "In10.Cu" signal "GND4")
		(24 "In11.Cu" signal "IN4")
		(26 "In12.Cu" signal "GND5")
		(28 "In13.Cu" signal "IN5")
		(30 "In14.Cu" signal "GND6")
		(32 "In15.Cu" signal "IN6")
		(34 "In16.Cu" signal "GND7")
		(2 "B.Cu" signal "BOTTOM")
		(9 "F.Adhes" user "F.Adhesive")
		(11 "B.Adhes" user "B.Adhesive")
		(13 "F.Paste" user "Package Geometry/Pastemask Top")
		(15 "B.Paste" user "Package Geometry/Pastemask Bottom")
		(5 "F.SilkS" user "Ref Des/Silkscreen Top")
		(7 "B.SilkS" user "Ref Des/Silkscreen Bottom")
		(1 "F.Mask" user "Board Geometry/Soldermask Top")
		(3 "B.Mask" user "Board Geometry/Soldermask Bottom")
		(17 "Dwgs.User" user "User.Drawings")
		(19 "Cmts.User" user "User.Comments")
		(21 "Eco1.User" user "User.Eco1")
		(23 "Eco2.User" user "User.Eco2")
		(25 "Edge.Cuts" user "Board Geometry/Outline")
		(27 "Margin" user)
		(31 "F.CrtYd" user "Package Geometry/Place Bound Top")
		(29 "B.CrtYd" user "Package Geometry/Place Bound Bottom")
		(35 "F.Fab" user "Ref Des/Assembly Top")
		(33 "B.Fab" user "Ref Des/Assembly Bottom")
	)
	(footprint ""
		(layer "F.Cu")
		(at 137.762488 -384.10388 180)
		(property "Reference" "R897"
			(at 0 0 180)
			(layer "F.SilkS")
			(hide yes)
			(effects
				(font
					(size 1.27 1.27)
				)
			)
		)
		(property "Value" ""
			(at 0 0 180)
			(layer "F.Fab")
			(effects
				(font
					(size 1.27 1.27)
				)
			)
		)
		(duplicate_pad_numbers_are_jumpers no)
		(fp_line
			(start 0.7874 0.4064)
			(end -0.7874 0.4064)
			(stroke
				(width 0.1524)
				(type default)
			)
			(layer "F.SilkS")
		)
		(fp_line
			(start 0.7874 -0.4064)
			(end 0.7874 0.4064)
			(stroke
				(width 0.1524)
				(type default)
			)
			(layer "F.SilkS")
		)
		(fp_line
			(start -0.7874 0.4064)
			(end -0.7874 -0.4064)
			(stroke
				(width 0.1524)
				(type default)
			)
			(layer "F.SilkS")
		)
		(fp_line
			(start -0.7874 -0.4064)
			(end 0.7874 -0.4064)
			(stroke
				(width 0.1524)
				(type default)
			)
			(layer "F.SilkS")
		)
		(fp_line
			(start 0.67945 0.3048)
			(end 0.120396 0.3048)
			(stroke
				(width 0.1)
				(type default)
			)
			(layer "F.Fab")
		)
		(fp_line
			(start 0.67945 -0.3048)
			(end 0.67945 0.3048)
			(stroke
				(width 0.1)
				(type default)
			)
			(layer "F.Fab")
		)
		(fp_line
			(start 0.12065 -0.2794)
			(end 0.12065 -0.3048)
			(stroke
				(width 0.1)
				(type default)
			)
			(layer "F.Fab")
		)
		(fp_line
			(start 0.12065 -0.3048)
			(end 0.67945 -0.3048)
			(stroke
				(width 0.1)
				(type default)
			)
			(layer "F.Fab")
		)
		(fp_line
			(start 0.120396 0.3048)
			(end 0.120396 0.2794)
			(stroke
				(width 0.1)
				(type default)
			)
			(layer "F.Fab")
		)
		(fp_line
			(start 0.120396 0.2794)
			(end -0.12065 0.2794)
			(stroke
				(width 0.1)
				(type default)
			)
			(layer "F.Fab")
		)
		(fp_line
			(start -0.12065 0.3048)
			(end -0.67945 0.3048)
			(stroke
				(width 0.1)
				(type default)
			)
			(layer "F.Fab")
		)
		(fp_line
			(start -0.12065 0.2794)
			(end -0.12065 0.3048)
			(stroke
				(width 0.1)
				(type default)
			)
			(layer "F.Fab")
		)
		(fp_line
			(start -0.12065 -0.2794)
			(end 0.12065 -0.2794)
			(stroke
				(width 0.1)
				(type default)
			)
			(layer "F.Fab")
		)
		(fp_line
			(start -0.12065 -0.305054)
			(end -0.12065 -0.2794)
			(stroke
				(width 0.1)
				(type default)
			)
			(layer "F.Fab")
		)
		(fp_line
			(start -0.67945 0.3048)
			(end -0.67945 -0.305054)
			(stroke
				(width 0.1)
				(type default)
			)
			(layer "F.Fab")
		)
		(fp_line
			(start -0.67945 -0.305054)
			(end -0.12065 -0.305054)
			(stroke
				(width 0.1)
				(type default)
			)
			(layer "F.Fab")
		)
		(pad "1" smd rect
			(at -0.40005 0)
			(size 0.4572 0.508)
			(layers "F.Cu" "F.Mask" "F.Paste")
			(net "P1V8_CPU1_RT_1D")
		)
		(pad "2" smd rect
			(at 0.40005 0)
			(size 0.4572 0.508)
			(layers "F.Cu" "F.Mask" "F.Paste")
			(net "P1V8_CPU1_RT3_1A_1D")
		)
	)
	(footprint ""
		(layer "F.Cu")
		(at 194.183 -133.568948 90)
		(property "Reference" "R3482"
			(at 0 0 90)
			(layer "F.SilkS")
			(hide yes)
			(effects
				(font
					(size 1.27 1.27)
				)
			)
		)
		(property "Value" ""
			(at 0 0 90)
			(layer "F.Fab")
			(effects
				(font
					(size 1.27 1.27)
				)
			)
		)
		(duplicate_pad_numbers_are_jumpers no)
		(fp_line
			(start 0.7874 -0.4064)
			(end 0.7874 0.4064)
			(stroke
				(width 0.1524)
				(type default)
			)
			(layer "F.SilkS")
		)
		(fp_line
			(start -0.7874 -0.4064)
			(end 0.7874 -0.4064)
			(stroke
				(width 0.1524)
				(type default)
			)
			(layer "F.SilkS")
		)
		(fp_line
			(start 0.7874 0.4064)
			(end -0.7874 0.4064)
			(stroke
				(width 0.1524)
				(type default)
			)
			(layer "F.SilkS")
		)
		(fp_line
			(start -0.7874 0.4064)
			(end -0.7874 -0.4064)
			(stroke
				(width 0.1524)
				(type default)
			)
			(layer "F.SilkS")
		)
		(fp_line
			(start -0.12065 -0.305054)
			(end -0.12065 -0.2794)
			(stroke
				(width 0.1)
				(type default)
			)
			(layer "F.Fab")
		)
		(fp_line
			(start -0.67945 -0.305054)
			(end -0.12065 -0.305054)
			(stroke
				(width 0.1)
				(type default)
			)
			(layer "F.Fab")
		)
		(fp_line
			(start 0.67945 -0.3048)
			(end 0.67945 0.3048)
			(stroke
				(width 0.1)
				(type default)
			)
			(layer "F.Fab")
		)
		(fp_line
			(start 0.12065 -0.3048)
			(end 0.67945 -0.3048)
			(stroke
				(width 0.1)
				(type default)
			)
			(layer "F.Fab")
		)
		(fp_line
			(start 0.12065 -0.2794)
			(end 0.12065 -0.3048)
			(stroke
				(width 0.1)
				(type default)
			)
			(layer "F.Fab")
		)
		(fp_line
			(start -0.12065 -0.2794)
			(end 0.12065 -0.2794)
			(stroke
				(width 0.1)
				(type default)
			)
			(layer "F.Fab")
		)
		(fp_line
			(start 0.120396 0.2794)
			(end -0.12065 0.2794)
			(stroke
				(width 0.1)
				(type default)
			)
			(layer "F.Fab")
		)
		(fp_line
			(start -0.12065 0.2794)
			(end -0.12065 0.3048)
			(stroke
				(width 0.1)
				(type default)
			)
			(layer "F.Fab")
		)
		(fp_line
			(start 0.67945 0.3048)
			(end 0.120396 0.3048)
			(stroke
				(width 0.1)
				(type default)
			)
			(layer "F.Fab")
		)
		(fp_line
			(start 0.120396 0.3048)
			(end 0.120396 0.2794)
			(stroke
				(width 0.1)
				(type default)
			)
			(layer "F.Fab")
		)
		(fp_line
			(start -0.12065 0.3048)
			(end -0.67945 0.3048)
			(stroke
				(width 0.1)
				(type default)
			)
			(layer "F.Fab")
		)
		(fp_line
			(start -0.67945 0.3048)
			(end -0.67945 -0.305054)
			(stroke
				(width 0.1)
				(type default)
			)
			(layer "F.Fab")
		)
		(pad "1" smd circle
			(at -0.40005 0 90)
			(size 0 0)
			(layers "F.Cu" "F.Mask" "F.Paste")
			(net "GPU_FPGA_BOOT_EN_R")
		)
		(pad "2" smd circle
			(at 0.40005 0 90)
			(size 0 0)
			(layers "F.Cu" "F.Mask" "F.Paste")
			(net "GPU_FPGA_BOOT_EN")
		)
	)
	(footprint ""
		(layer "F.Cu")
		(at 185.799222 -22.097492 180)
		(property "Reference" "PR4002"
			(at 0 0 180)
			(layer "F.SilkS")
			(hide yes)
			(effects
				(font
					(size 1.27 1.27)
				)
			)
		)
		(property "Value" ""
			(at 0 0 180)
			(layer "F.Fab")
			(effects
				(font
					(size 1.27 1.27)
				)
			)
		)
		(duplicate_pad_numbers_are_jumpers no)
		(fp_line
			(start 0.7874 0.4064)
			(end -0.7874 0.4064)
			(stroke
				(width 0.1524)
				(type default)
			)
			(layer "F.SilkS")
		)
		(fp_line
			(start 0.7874 -0.4064)
			(end 0.7874 0.4064)
			(stroke
				(width 0.1524)
				(type default)
			)
			(layer "F.SilkS")
		)
		(fp_line
			(start -0.7874 0.4064)
			(end -0.7874 -0.4064)
			(stroke
				(width 0.1524)
				(type default)
			)
			(layer "F.SilkS")
		)
		(fp_line
			(start -0.7874 -0.4064)
			(end 0.7874 -0.4064)
			(stroke
				(width 0.1524)
				(type default)
			)
			(layer "F.SilkS")
		)
		(fp_line
			(start 0.67945 0.3048)
			(end 0.120396 0.3048)
			(stroke
				(width 0.1)
				(type default)
			)
			(layer "F.Fab")
		)
		(fp_line
			(start 0.67945 -0.3048)
			(end 0.67945 0.3048)
			(stroke
				(width 0.1)
				(type default)
			)
			(layer "F.Fab")
		)
		(fp_line
			(start 0.12065 -0.2794)
			(end 0.12065 -0.3048)
			(stroke
				(width 0.1)
				(type default)
			)
			(layer "F.Fab")
		)
		(fp_line
			(start 0.12065 -0.3048)
			(end 0.67945 -0.3048)
			(stroke
				(width 0.1)
				(type default)
			)
			(layer "F.Fab")
		)
		(fp_line
			(start 0.120396 0.3048)
			(end 0.120396 0.2794)
			(stroke
				(width 0.1)
				(type default)
			)
			(layer "F.Fab")
		)
		(fp_line
			(start 0.120396 0.2794)
			(end -0.12065 0.2794)
			(stroke
				(width 0.1)
				(type default)
			)
			(layer "F.Fab")
		)
		(fp_line
			(start -0.12065 0.3048)
			(end -0.67945 0.3048)
			(stroke
				(width 0.1)
				(type default)
			)
			(layer "F.Fab")
		)
		(fp_line
			(start -0.12065 0.2794)
			(end -0.12065 0.3048)
			(stroke
				(width 0.1)
				(type default)
			)
			(layer "F.Fab")
		)
		(fp_line
			(start -0.12065 -0.2794)
			(end 0.12065 -0.2794)
			(stroke
				(width 0.1)
				(type default)
			)
			(layer "F.Fab")
		)
		(fp_line
			(start -0.12065 -0.305054)
			(end -0.12065 -0.2794)
			(stroke
				(width 0.1)
				(type default)
			)
			(layer "F.Fab")
		)
		(fp_line
			(start -0.67945 0.3048)
			(end -0.67945 -0.305054)
			(stroke
				(width 0.1)
				(type default)
			)
			(layer "F.Fab")
		)
		(fp_line
			(start -0.67945 -0.305054)
			(end -0.12065 -0.305054)
			(stroke
				(width 0.1)
				(type default)
			)
			(layer "F.Fab")
		)
		(pad "1" smd circle
			(at -0.40005 0 180)
			(size 0 0)
			(layers "F.Cu" "F.Mask" "F.Paste")
			(net "P12V_SCM_OV")
		)
		(pad "2" smd circle
			(at 0.40005 0 180)
			(size 0 0)
			(layers "F.Cu" "F.Mask" "F.Paste")
			(net "GND")
		)
	)
	(footprint ""
		(layer "F.Cu")
		(at 68.225162 -34.874708 180)
		(property "Reference" "R1181"
			(at 0 0 180)
			(layer "F.SilkS")
			(hide yes)
			(effects
				(font
					(size 1.27 1.27)
				)
			)
		)
		(property "Value" ""
			(at 0 0 180)
			(layer "F.Fab")
			(effects
				(font
					(size 1.27 1.27)
				)
			)
		)
		(duplicate_pad_numbers_are_jumpers no)
		(fp_line
			(start 0.7874 0.4064)
			(end -0.7874 0.4064)
			(stroke
				(width 0.1524)
				(type default)
			)
			(layer "F.SilkS")
		)
		(fp_line
			(start 0.7874 -0.4064)
			(end 0.7874 0.4064)
			(stroke
				(width 0.1524)
				(type default)
			)
			(layer "F.SilkS")
		)
		(fp_line
			(start -0.7874 0.4064)
			(end -0.7874 -0.4064)
			(stroke
				(width 0.1524)
				(type default)
			)
			(layer "F.SilkS")
		)
		(fp_line
			(start -0.7874 -0.4064)
			(end 0.7874 -0.4064)
			(stroke
				(width 0.1524)
				(type default)
			)
			(layer "F.SilkS")
		)
		(fp_line
			(start 0.67945 0.3048)
			(end 0.120396 0.3048)
			(stroke
				(width 0.1)
				(type default)
			)
			(layer "F.Fab")
		)
		(fp_line
			(start 0.67945 -0.3048)
			(end 0.67945 0.3048)
			(stroke
				(width 0.1)
				(type default)
			)
			(layer "F.Fab")
		)
		(fp_line
			(start 0.12065 -0.2794)
			(end 0.12065 -0.3048)
			(stroke
				(width 0.1)
				(type default)
			)
			(layer "F.Fab")
		)
		(fp_line
			(start 0.12065 -0.3048)
			(end 0.67945 -0.3048)
			(stroke
				(width 0.1)
				(type default)
			)
			(layer "F.Fab")
		)
		(fp_line
			(start 0.120396 0.3048)
			(end 0.120396 0.2794)
			(stroke
				(width 0.1)
				(type default)
			)
			(layer "F.Fab")
		)
		(fp_line
			(start 0.120396 0.2794)
			(end -0.12065 0.2794)
			(stroke
				(width 0.1)
				(type default)
			)
			(layer "F.Fab")
		)
		(fp_line
			(start -0.12065 0.3048)
			(end -0.67945 0.3048)
			(stroke
				(width 0.1)
				(type default)
			)
			(layer "F.Fab")
		)
		(fp_line
			(start -0.12065 0.2794)
			(end -0.12065 0.3048)
			(stroke
				(width 0.1)
				(type default)
			)
			(layer "F.Fab")
		)
		(fp_line
			(start -0.12065 -0.2794)
			(end 0.12065 -0.2794)
			(stroke
				(width 0.1)
				(type default)
			)
			(layer "F.Fab")
		)
		(fp_line
			(start -0.12065 -0.305054)
			(end -0.12065 -0.2794)
			(stroke
				(width 0.1)
				(type default)
			)
			(layer "F.Fab")
		)
		(fp_line
			(start -0.67945 0.3048)
			(end -0.67945 -0.305054)
			(stroke
				(width 0.1)
				(type default)
			)
			(layer "F.Fab")
		)
		(fp_line
			(start -0.67945 -0.305054)
			(end -0.12065 -0.305054)
			(stroke
				(width 0.1)
				(type default)
			)
			(layer "F.Fab")
		)
		(pad "1" smd circle
			(at -0.40005 0 180)
			(size 0 0)
			(layers "F.Cu" "F.Mask" "F.Paste")
			(net "P12V_OCP_V3_2_BUF_EN_R")
		)
		(pad "2" smd circle
			(at 0.40005 0 180)
			(size 0 0)
			(layers "F.Cu" "F.Mask" "F.Paste")
			(net "P12V_OCP_EN_2_R")
		)
	)
	(footprint ""
		(layer "F.Cu")
		(at 303.573434 -427.1391 -90)
		(property "Reference" "Q130"
			(at 1.471676 -1.958848 90)
			(unlocked yes)
			(layer "F.SilkS")
			(effects
				(font
					(size 0.7874 0.5842)
					(thickness 0.1524)
				)
				(justify left)
			)
		)
		(property "Value" ""
			(at 0 0 270)
			(layer "F.Fab")
			(effects
				(font
					(size 1.27 1.27)
				)
			)
		)
		(duplicate_pad_numbers_are_jumpers no)
		(fp_line
			(start -1.332738 1.100074)
			(end -1.332738 -1.100074)
			(stroke
				(width 0.1524)
				(type default)
			)
			(layer "F.SilkS")
		)
		(fp_line
			(start 1.332738 1.100074)
			(end -1.332738 1.100074)
			(stroke
				(width 0.1524)
				(type default)
			)
			(layer "F.SilkS")
		)
		(fp_line
			(start 0 -0.541274)
			(end 0.4826 -1.100074)
			(stroke
				(width 0.1524)
				(type default)
			)
			(layer "F.SilkS")
		)
		(fp_line
			(start -1.332738 -1.100074)
			(end -0.4826 -1.100074)
			(stroke
				(width 0.1524)
				(type default)
			)
			(layer "F.SilkS")
		)
		(fp_line
			(start -0.4826 -1.100074)
			(end 0 -0.541274)
			(stroke
				(width 0.1524)
				(type default)
			)
			(layer "F.SilkS")
		)
		(fp_line
			(start 0.4826 -1.100074)
			(end 1.332738 -1.100074)
			(stroke
				(width 0.1524)
				(type default)
			)
			(layer "F.SilkS")
		)
		(fp_line
			(start 1.332738 -1.100074)
			(end 1.332738 1.100074)
			(stroke
				(width 0.1524)
				(type default)
			)
			(layer "F.SilkS")
		)
		(fp_poly
			(pts
				(xy -1.542542 -1.16332) (xy -2.287016 -1.411478) (xy -1.7907 -1.908048)
			)
			(stroke
				(width 0)
				(type default)
			)
			(fill yes)
			(layer "F.SilkS")
		)
		(fp_line
			(start -0.674878 1.100074)
			(end -0.674878 -1.100074)
			(stroke
				(width 0.1)
				(type default)
			)
			(layer "F.Fab")
		)
		(fp_line
			(start 0.674878 1.100074)
			(end -0.674878 1.100074)
			(stroke
				(width 0.1)
				(type default)
			)
			(layer "F.Fab")
		)
		(fp_line
			(start -0.674878 -1.100074)
			(end 0.674878 -1.100074)
			(stroke
				(width 0.1)
				(type default)
			)
			(layer "F.Fab")
		)
		(fp_line
			(start 0.674878 -1.100074)
			(end 0.674878 1.100074)
			(stroke
				(width 0.1)
				(type default)
			)
			(layer "F.Fab")
		)
		(fp_poly
			(pts
				(xy -2.2352 -0.298958) (xy -2.2352 -1.001014) (xy -1.533144 -0.649986)
			)
			(stroke
				(width 0)
				(type default)
			)
			(fill yes)
			(layer "F.Fab")
		)
		(pad "1" smd rect
			(at -0.94996 -0.649986)
			(size 0.4318 0.508)
			(layers "F.Cu" "F.Mask" "F.Paste")
			(net "GND")
		)
		(pad "2" smd rect
			(at -0.94996 0)
			(size 0.4318 0.508)
			(layers "F.Cu" "F.Mask" "F.Paste")
			(net "GPU_3V3IO_RSVD3_FFU")
		)
		(pad "3" smd rect
			(at -0.94996 0.649986)
			(size 0.4318 0.508)
			(layers "F.Cu" "F.Mask" "F.Paste")
			(net "GPU_3V3IO_RSVD3_FFU_ISO")
		)
		(pad "4" smd rect
			(at 0.94996 0.649986)
			(size 0.4318 0.508)
			(layers "F.Cu" "F.Mask" "F.Paste")
			(net "GND")
		)
		(pad "5" smd rect
			(at 0.94996 0)
			(size 0.4318 0.508)
			(layers "F.Cu" "F.Mask" "F.Paste")
			(net "GPU_3V3IO_RSVD3_FFU_N")
		)
		(pad "6" smd rect
			(at 0.94996 -0.649986)
			(size 0.4318 0.508)
			(layers "F.Cu" "F.Mask" "F.Paste")
			(net "GPU_3V3IO_RSVD3_FFU_N")
		)
	)
	(footprint ""
		(layer "F.Cu")
		(at 118.718584 -61.916056 180)
		(property "Reference" "R1748"
			(at 0 0 180)
			(layer "F.SilkS")
			(hide yes)
			(effects
				(font
					(size 1.27 1.27)
				)
			)
		)
		(property "Value" ""
			(at 0 0 180)
			(layer "F.Fab")
			(effects
				(font
					(size 1.27 1.27)
				)
			)
		)
		(duplicate_pad_numbers_are_jumpers no)
		(fp_line
			(start 0.7874 0.4064)
			(end -0.7874 0.4064)
			(stroke
				(width 0.1524)
				(type default)
			)
			(layer "F.SilkS")
		)
		(fp_line
			(start 0.7874 -0.4064)
			(end 0.7874 0.4064)
			(stroke
				(width 0.1524)
				(type default)
			)
			(layer "F.SilkS")
		)
		(fp_line
			(start -0.7874 0.4064)
			(end -0.7874 -0.4064)
			(stroke
				(width 0.1524)
				(type default)
			)
			(layer "F.SilkS")
		)
		(fp_line
			(start -0.7874 -0.4064)
			(end 0.7874 -0.4064)
			(stroke
				(width 0.1524)
				(type default)
			)
			(layer "F.SilkS")
		)
		(fp_line
			(start 0.67945 0.3048)
			(end 0.120396 0.3048)
			(stroke
				(width 0.1)
				(type default)
			)
			(layer "F.Fab")
		)
		(fp_line
			(start 0.67945 -0.3048)
			(end 0.67945 0.3048)
			(stroke
				(width 0.1)
				(type default)
			)
			(layer "F.Fab")
		)
		(fp_line
			(start 0.12065 -0.2794)
			(end 0.12065 -0.3048)
			(stroke
				(width 0.1)
				(type default)
			)
			(layer "F.Fab")
		)
		(fp_line
			(start 0.12065 -0.3048)
			(end 0.67945 -0.3048)
			(stroke
				(width 0.1)
				(type default)
			)
			(layer "F.Fab")
		)
		(fp_line
			(start 0.120396 0.3048)
			(end 0.120396 0.2794)
			(stroke
				(width 0.1)
				(type default)
			)
			(layer "F.Fab")
		)
		(fp_line
			(start 0.120396 0.2794)
			(end -0.12065 0.2794)
			(stroke
				(width 0.1)
				(type default)
			)
			(layer "F.Fab")
		)
		(fp_line
			(start -0.12065 0.3048)
			(end -0.67945 0.3048)
			(stroke
				(width 0.1)
				(type default)
			)
			(layer "F.Fab")
		)
		(fp_line
			(start -0.12065 0.2794)
			(end -0.12065 0.3048)
			(stroke
				(width 0.1)
				(type default)
			)
			(layer "F.Fab")
		)
		(fp_line
			(start -0.12065 -0.2794)
			(end 0.12065 -0.2794)
			(stroke
				(width 0.1)
				(type default)
			)
			(layer "F.Fab")
		)
		(fp_line
			(start -0.12065 -0.305054)
			(end -0.12065 -0.2794)
			(stroke
				(width 0.1)
				(type default)
			)
			(layer "F.Fab")
		)
		(fp_line
			(start -0.67945 0.3048)
			(end -0.67945 -0.305054)
			(stroke
				(width 0.1)
				(type default)
			)
			(layer "F.Fab")
		)
		(fp_line
			(start -0.67945 -0.305054)
			(end -0.12065 -0.305054)
			(stroke
				(width 0.1)
				(type default)
			)
			(layer "F.Fab")
		)
		(pad "1" smd circle
			(at -0.40005 0 180)
			(size 0 0)
			(layers "F.Cu" "F.Mask" "F.Paste")
			(net "JTAG_SCM_MUX_TCK")
		)
		(pad "2" smd circle
			(at 0.40005 0 180)
			(size 0 0)
			(layers "F.Cu" "F.Mask" "F.Paste")
			(net "GND")
		)
	)
)
